(kicad_pcb
	(version 20260206)
	(generator "pcbnew")
	(generator_version "10.0")
	(general
		(thickness 1.6)
		(legacy_teardrops no)
	)
	(paper "A4")
	(title_block
		(title "Bryce Canyon_F.DPB_16315-1-OCP.brd")
		(comment 1 "Bryce Canyon / footprints 1394-1399 of 2223")
	)
	(layers
		(0 "F.Cu" signal "TOP")
		(4 "In1.Cu" signal "L2GND")
		(6 "In2.Cu" signal "L3")
		(8 "In3.Cu" signal "L4GND")
		(10 "In4.Cu" signal "L5")
		(12 "In5.Cu" signal "L6VCC")
		(14 "In6.Cu" signal "L7VCC")
		(16 "In7.Cu" signal "L8")
		(18 "In8.Cu" signal "L9GND")
		(20 "In9.Cu" signal "L10")
		(22 "In10.Cu" signal "L11GND")
		(2 "B.Cu" signal "BOTTOM")
		(9 "F.Adhes" user "F.Adhesive")
		(11 "B.Adhes" user "B.Adhesive")
		(13 "F.Paste" user "Package Geometry/Pastemask Top")
		(15 "B.Paste" user "Package Geometry/Pastemask Bottom")
		(5 "F.SilkS" user "Ref Des/Silkscreen Top")
		(7 "B.SilkS" user "Ref Des/Silkscreen Bottom")
		(1 "F.Mask" user "Board Geometry/Soldermask Top")
		(3 "B.Mask" user "Board Geometry/Soldermask Bottom")
		(17 "Dwgs.User" user "User.Drawings")
		(19 "Cmts.User" user "User.Comments")
		(21 "Eco1.User" user "User.Eco1")
		(23 "Eco2.User" user "User.Eco2")
		(25 "Edge.Cuts" user "Board Geometry/Outline")
		(27 "Margin" user)
		(31 "F.CrtYd" user "Package Geometry/Place Bound Top")
		(29 "B.CrtYd" user "Package Geometry/Place Bound Bottom")
		(35 "F.Fab" user "Ref Des/Assembly Top")
		(33 "B.Fab" user "Ref Des/Assembly Bottom")
	)
	(footprint ""
		(layer "F.Cu")
		(at 266.2936 -230.3018 180)
		(property "Reference" "R90"
			(at 0 0 180)
			(layer "F.SilkS")
			(hide yes)
			(effects
				(font
					(size 1.27 1.27)
				)
			)
		)
		(property "Value" "4K7R2F-GP"
			(at 0.064008 -3.993896 180)
			(unlocked yes)
			(layer "F.Fab")
			(hide yes)
			(effects
				(font
					(size 1.016 1.016)
					(thickness 0.1524)
				)
			)
		)
		(property "Device Type" "R402H16"
			(at 0.064008 -5.517896 180)
			(unlocked yes)
			(layer "F.Fab")
			(hide yes)
			(effects
				(font
					(size 1.016 1.016)
					(thickness 0.1524)
				)
			)
		)
		(duplicate_pad_numbers_are_jumpers no)
		(fp_line
			(start 0.508 -0.9398)
			(end -0.508 -0.9398)
			(stroke
				(width 0.1524)
				(type default)
			)
			(layer "F.SilkS")
		)
		(fp_line
			(start -0.508 -0.9398)
			(end -0.508 0.9398)
			(stroke
				(width 0.1524)
				(type default)
			)
			(layer "F.SilkS")
		)
		(fp_rect
			(start -0.508 0.9398)
			(end 0.508 -0.9398)
			(stroke
				(width 0)
				(type default)
			)
			(fill no)
			(layer "F.CrtYd")
		)
		(fp_rect
			(start -0.508 0.9398)
			(end 0.508 -0.9398)
			(stroke
				(width 0)
				(type default)
			)
			(fill no)
			(layer "F.Fab")
		)
		(pad "1" smd custom
			(at 0 -0.4445 180)
			(size 0.1397 0.1397)
			(layers "F.Cu" "F.Mask" "F.Paste")
			(net "P3V3_STBY_A")
			(options
				(clearance outline)
				(anchor circle)
			)
			(primitives
				(gr_poly
					(pts
						(arc
							(start -0.1778 -0.2794)
							(mid -0.249642 -0.249642)
							(end -0.2794 -0.1778)
						)
						(arc
							(start -0.2794 0.1778)
							(mid -0.249642 0.249642)
							(end -0.1778 0.2794)
						)
						(arc
							(start 0.1778 0.2794)
							(mid 0.249642 0.249642)
							(end 0.2794 0.1778)
						)
						(arc
							(start 0.2794 -0.1778)
							(mid 0.249642 -0.249642)
							(end 0.1778 -0.2794)
						)
					)
					(width 0)
					(fill yes)
				)
			)
		)
		(pad "2" smd custom
			(at 0 0.4445 180)
			(size 0.1397 0.1397)
			(layers "F.Cu" "F.Mask" "F.Paste")
			(net "IO_EXP3_A1")
			(options
				(clearance outline)
				(anchor circle)
			)
			(primitives
				(gr_poly
					(pts
						(arc
							(start -0.1778 -0.2794)
							(mid -0.249642 -0.249642)
							(end -0.2794 -0.1778)
						)
						(arc
							(start -0.2794 0.1778)
							(mid -0.249642 0.249642)
							(end -0.1778 0.2794)
						)
						(arc
							(start 0.1778 0.2794)
							(mid 0.249642 0.249642)
							(end 0.2794 0.1778)
						)
						(arc
							(start 0.2794 -0.1778)
							(mid 0.249642 -0.249642)
							(end 0.1778 -0.2794)
						)
					)
					(width 0)
					(fill yes)
				)
			)
		)
	)
	(footprint ""
		(layer "F.Cu")
		(at 474.853 -162.687)
		(property "Reference" "R663"
			(at 0 0 0)
			(layer "F.SilkS")
			(hide yes)
			(effects
				(font
					(size 1.27 1.27)
				)
			)
		)
		(property "Value" "220R3F-1-GP"
			(at -0.0254 -2.5146 0)
			(unlocked yes)
			(layer "F.Fab")
			(hide yes)
			(effects
				(font
					(size 1.016 1.016)
					(thickness 0.1524)
				)
			)
		)
		(property "Device Type" "R603H22"
			(at -0.0254 -4.0386 0)
			(unlocked yes)
			(layer "F.Fab")
			(hide yes)
			(effects
				(font
					(size 1.016 1.016)
					(thickness 0.1524)
				)
			)
		)
		(duplicate_pad_numbers_are_jumpers no)
		(fp_line
			(start -0.4826 0)
			(end -0.2032 0)
			(stroke
				(width 0.2032)
				(type default)
			)
			(layer "F.SilkS")
		)
		(fp_line
			(start 0.2032 0)
			(end 0.4826 0)
			(stroke
				(width 0.2032)
				(type default)
			)
			(layer "F.SilkS")
		)
		(fp_rect
			(start -0.5842 1.3335)
			(end 0.5842 -1.3335)
			(stroke
				(width 0)
				(type default)
			)
			(fill no)
			(layer "F.CrtYd")
		)
		(fp_rect
			(start -0.5842 1.3335)
			(end 0.5842 -1.3335)
			(stroke
				(width 0)
				(type default)
			)
			(fill no)
			(layer "F.Fab")
		)
		(pad "1" smd custom
			(at 0 -0.762)
			(size 0.2159 0.2159)
			(layers "F.Cu" "F.Mask" "F.Paste")
			(net "HDD_PRSNT_23")
			(options
				(clearance outline)
				(anchor circle)
			)
			(primitives
				(gr_poly
					(pts
						(arc
							(start -0.3302 -0.4318)
							(mid -0.402042 -0.402042)
							(end -0.4318 -0.3302)
						)
						(arc
							(start -0.4318 0.3302)
							(mid -0.402042 0.402042)
							(end -0.3302 0.4318)
						)
						(arc
							(start 0.3302 0.4318)
							(mid 0.402042 0.402042)
							(end 0.4318 0.3302)
						)
						(arc
							(start 0.4318 -0.3302)
							(mid 0.402042 -0.402042)
							(end 0.3302 -0.4318)
						)
					)
					(width 0)
					(fill yes)
				)
			)
		)
		(pad "2" smd custom
			(at 0 0.762)
			(size 0.2159 0.2159)
			(layers "F.Cu" "F.Mask" "F.Paste")
			(net "DRIVE_A_23_INS")
			(options
				(clearance outline)
				(anchor circle)
			)
			(primitives
				(gr_poly
					(pts
						(arc
							(start -0.3302 -0.4318)
							(mid -0.402042 -0.402042)
							(end -0.4318 -0.3302)
						)
						(arc
							(start -0.4318 0.3302)
							(mid -0.402042 0.402042)
							(end -0.3302 0.4318)
						)
						(arc
							(start 0.3302 0.4318)
							(mid 0.402042 0.402042)
							(end 0.4318 0.3302)
						)
						(arc
							(start 0.4318 -0.3302)
							(mid 0.402042 -0.402042)
							(end 0.3302 -0.4318)
						)
					)
					(width 0)
					(fill yes)
				)
			)
		)
	)
	(footprint ""
		(layer "F.Cu")
		(at 342.420702 -130.386836 -90)
		(property "Reference" "R532"
			(at 0 0 270)
			(layer "F.SilkS")
			(hide yes)
			(effects
				(font
					(size 1.27 1.27)
				)
			)
		)
		(property "Value" "4K7R2J-2-GP"
			(at 0.064008 -3.993896 270)
			(unlocked yes)
			(layer "F.Fab")
			(hide yes)
			(effects
				(font
					(size 1.016 1.016)
					(thickness 0.1524)
				)
			)
		)
		(property "Device Type" "R402H16"
			(at 0.064008 -5.517896 270)
			(unlocked yes)
			(layer "F.Fab")
			(hide yes)
			(effects
				(font
					(size 1.016 1.016)
					(thickness 0.1524)
				)
			)
		)
		(duplicate_pad_numbers_are_jumpers no)
		(fp_line
			(start -0.508 -0.9398)
			(end -0.508 0.9398)
			(stroke
				(width 0.1524)
				(type default)
			)
			(layer "F.SilkS")
		)
		(fp_line
			(start 0.508 -0.9398)
			(end -0.508 -0.9398)
			(stroke
				(width 0.1524)
				(type default)
			)
			(layer "F.SilkS")
		)
		(fp_rect
			(start -0.508 0.9398)
			(end 0.508 -0.9398)
			(stroke
				(width 0)
				(type default)
			)
			(fill no)
			(layer "F.CrtYd")
		)
		(fp_rect
			(start -0.508 0.9398)
			(end 0.508 -0.9398)
			(stroke
				(width 0)
				(type default)
			)
			(fill no)
			(layer "F.Fab")
		)
		(pad "1" smd custom
			(at 0 -0.4445 270)
			(size 0.1397 0.1397)
			(layers "F.Cu" "F.Mask" "F.Paste")
			(net "DRIVE_A_19_FLT_LED")
			(options
				(clearance outline)
				(anchor circle)
			)
			(primitives
				(gr_poly
					(pts
						(arc
							(start -0.1778 -0.2794)
							(mid -0.249642 -0.249642)
							(end -0.2794 -0.1778)
						)
						(arc
							(start -0.2794 0.1778)
							(mid -0.249642 0.249642)
							(end -0.1778 0.2794)
						)
						(arc
							(start 0.1778 0.2794)
							(mid 0.249642 0.249642)
							(end 0.2794 0.1778)
						)
						(arc
							(start 0.2794 -0.1778)
							(mid 0.249642 -0.249642)
							(end 0.1778 -0.2794)
						)
					)
					(width 0)
					(fill yes)
				)
			)
		)
		(pad "2" smd custom
			(at 0 0.4445 270)
			(size 0.1397 0.1397)
			(layers "F.Cu" "F.Mask" "F.Paste")
			(net "GND")
			(options
				(clearance outline)
				(anchor circle)
			)
			(primitives
				(gr_poly
					(pts
						(arc
							(start -0.1778 -0.2794)
							(mid -0.249642 -0.249642)
							(end -0.2794 -0.1778)
						)
						(arc
							(start -0.2794 0.1778)
							(mid -0.249642 0.249642)
							(end -0.1778 0.2794)
						)
						(arc
							(start 0.1778 0.2794)
							(mid 0.249642 0.249642)
							(end 0.2794 0.1778)
						)
						(arc
							(start 0.2794 -0.1778)
							(mid 0.249642 -0.249642)
							(end 0.1778 -0.2794)
						)
					)
					(width 0)
					(fill yes)
				)
			)
		)
	)
	(footprint ""
		(layer "F.Cu")
		(at 115.334796 -170.285918 180)
		(property "Reference" "Q89"
			(at 0 0 180)
			(layer "F.SilkS")
			(hide yes)
			(effects
				(font
					(size 1.27 1.27)
				)
			)
		)
		(property "Value" "AO4406AL-GP"
			(at -3.707384 -1.5367 180)
			(unlocked yes)
			(layer "F.Fab")
			(hide yes)
			(effects
				(font
					(size 1.016 1.016)
					(thickness 0.1524)
				)
			)
		)
		(property "Device Type" "SOIC8H69"
			(at -3.707384 -3.0607 180)
			(unlocked yes)
			(layer "F.Fab")
			(hide yes)
			(effects
				(font
					(size 1.016 1.016)
					(thickness 0.1524)
				)
			)
		)
		(duplicate_pad_numbers_are_jumpers no)
		(fp_line
			(start 2.1336 1.4224)
			(end 2.1336 -1.4224)
			(stroke
				(width 0.1524)
				(type default)
			)
			(layer "F.SilkS")
		)
		(fp_line
			(start 2.1336 -1.4224)
			(end -2.7432 -1.4224)
			(stroke
				(width 0.1524)
				(type default)
			)
			(layer "F.SilkS")
		)
		(fp_line
			(start -2.1844 -0.0508)
			(end -2.7178 0.508)
			(stroke
				(width 0.1524)
				(type default)
			)
			(layer "F.SilkS")
		)
		(fp_line
			(start -2.6289 3.4417)
			(end -2.6289 1.4732)
			(stroke
				(width 0.381)
				(type default)
			)
			(layer "F.SilkS")
		)
		(fp_line
			(start -2.7178 -0.508)
			(end -2.1844 -0.0508)
			(stroke
				(width 0.1524)
				(type default)
			)
			(layer "F.SilkS")
		)
		(fp_line
			(start -2.7432 1.4224)
			(end 2.1336 1.4224)
			(stroke
				(width 0.1524)
				(type default)
			)
			(layer "F.SilkS")
		)
		(fp_line
			(start -2.7432 1.4224)
			(end -2.6416 1.4224)
			(stroke
				(width 0.1524)
				(type default)
			)
			(layer "F.SilkS")
		)
		(fp_line
			(start -2.7432 -1.4224)
			(end -2.7432 1.4224)
			(stroke
				(width 0.1524)
				(type default)
			)
			(layer "F.SilkS")
		)
		(fp_poly
			(pts
				(xy -2.2098 -1.4224) (xy -2.2098 1.4224) (xy 2.2098 1.4224) (xy 2.2098 -1.4224)
			)
			(stroke
				(width 0)
				(type default)
			)
			(fill yes)
			(layer "F.SilkS")
		)
		(fp_rect
			(start -2.450084 2.999994)
			(end 2.450084 -2.999994)
			(stroke
				(width 0)
				(type default)
			)
			(fill no)
			(layer "F.CrtYd")
		)
		(fp_poly
			(pts
				(xy -2.8194 3.6322) (xy -2.8194 -3.6322) (xy 2.8194 -3.6322) (xy 2.8194 1.18364) (xy 2.450084 1.18364)
				(xy 2.450084 -2.999994) (xy -2.450084 -2.999994) (xy -2.450084 2.999994) (xy 2.450084 2.999994)
				(xy 2.450084 1.18618) (xy 2.8194 1.18618) (xy 2.8194 3.6322)
			)
			(stroke
				(width 0)
				(type default)
			)
			(fill no)
			(layer "F.CrtYd")
		)
		(fp_rect
			(start -2.8194 3.6322)
			(end 2.8194 -3.6322)
			(stroke
				(width 0)
				(type default)
			)
			(fill no)
			(layer "F.Fab")
		)
		(pad "1" smd rect
			(at -1.905 2.54 180)
			(size 0.635 1.651)
			(layers "F.Cu" "F.Mask" "F.Paste")
			(net "P5V_HDD15")
		)
		(pad "2" smd rect
			(at -0.635 2.54 180)
			(size 0.635 1.651)
			(layers "F.Cu" "F.Mask" "F.Paste")
			(net "P5V_HDD15")
		)
		(pad "3" smd rect
			(at 0.635 2.54 180)
			(size 0.635 1.651)
			(layers "F.Cu" "F.Mask" "F.Paste")
			(net "P5V_HDD15")
		)
		(pad "4" smd rect
			(at 1.905 2.54 180)
			(size 0.635 1.651)
			(layers "F.Cu" "F.Mask" "F.Paste")
			(net "SW_HDD_P15")
		)
		(pad "5" smd rect
			(at 1.905 -2.54 180)
			(size 0.635 1.651)
			(layers "F.Cu" "F.Mask" "F.Paste")
			(net "P5V_A_2")
		)
		(pad "6" smd rect
			(at 0.635 -2.54 180)
			(size 0.635 1.651)
			(layers "F.Cu" "F.Mask" "F.Paste")
			(net "P5V_A_2")
		)
		(pad "7" smd rect
			(at -0.635 -2.54 180)
			(size 0.635 1.651)
			(layers "F.Cu" "F.Mask" "F.Paste")
			(net "P5V_A_2")
		)
		(pad "8" smd rect
			(at -1.905 -2.54 180)
			(size 0.635 1.651)
			(layers "F.Cu" "F.Mask" "F.Paste")
			(net "P5V_A_2")
		)
	)
	(footprint ""
		(layer "F.Cu")
		(at 399.90395 -62.016894)
		(property "Reference" "Q194"
			(at 0 0 0)
			(layer "F.SilkS")
			(hide yes)
			(effects
				(font
					(size 1.27 1.27)
				)
			)
		)
		(property "Value" "AO4407AL-GP"
			(at -3.707384 -1.5367 0)
			(unlocked yes)
			(layer "F.Fab")
			(hide yes)
			(effects
				(font
					(size 1.016 1.016)
					(thickness 0.1524)
				)
			)
		)
		(property "Device Type" "SOIC8H69"
			(at -3.707384 -3.0607 0)
			(unlocked yes)
			(layer "F.Fab")
			(hide yes)
			(effects
				(font
					(size 1.016 1.016)
					(thickness 0.1524)
				)
			)
		)
		(duplicate_pad_numbers_are_jumpers no)
		(fp_line
			(start -2.7432 -1.4224)
			(end -2.7432 1.4224)
			(stroke
				(width 0.1524)
				(type default)
			)
			(layer "F.SilkS")
		)
		(fp_line
			(start -2.7432 1.4224)
			(end -2.6416 1.4224)
			(stroke
				(width 0.1524)
				(type default)
			)
			(layer "F.SilkS")
		)
		(fp_line
			(start -2.7432 1.4224)
			(end 2.1336 1.4224)
			(stroke
				(width 0.1524)
				(type default)
			)
			(layer "F.SilkS")
		)
		(fp_line
			(start -2.7178 -0.508)
			(end -2.1844 -0.0508)
			(stroke
				(width 0.1524)
				(type default)
			)
			(layer "F.SilkS")
		)
		(fp_line
			(start -2.6289 3.4417)
			(end -2.6289 1.4732)
			(stroke
				(width 0.381)
				(type default)
			)
			(layer "F.SilkS")
		)
		(fp_line
			(start -2.1844 -0.0508)
			(end -2.7178 0.508)
			(stroke
				(width 0.1524)
				(type default)
			)
			(layer "F.SilkS")
		)
		(fp_line
			(start 2.1336 -1.4224)
			(end -2.7432 -1.4224)
			(stroke
				(width 0.1524)
				(type default)
			)
			(layer "F.SilkS")
		)
		(fp_line
			(start 2.1336 1.4224)
			(end 2.1336 -1.4224)
			(stroke
				(width 0.1524)
				(type default)
			)
			(layer "F.SilkS")
		)
		(fp_poly
			(pts
				(xy -2.2098 -1.4224) (xy -2.2098 1.4224) (xy 2.2098 1.4224) (xy 2.2098 -1.4224)
			)
			(stroke
				(width 0)
				(type default)
			)
			(fill yes)
			(layer "F.SilkS")
		)
		(fp_rect
			(start -2.450084 2.999994)
			(end 2.450084 -2.999994)
			(stroke
				(width 0)
				(type default)
			)
			(fill no)
			(layer "F.CrtYd")
		)
		(fp_poly
			(pts
				(xy -2.8194 3.6322) (xy -2.8194 -3.6322) (xy 2.8194 -3.6322) (xy 2.8194 1.18364) (xy 2.450084 1.18364)
				(xy 2.450084 -2.999994) (xy -2.450084 -2.999994) (xy -2.450084 2.999994) (xy 2.450084 2.999994)
				(xy 2.450084 1.18618) (xy 2.8194 1.18618) (xy 2.8194 3.6322)
			)
			(stroke
				(width 0)
				(type default)
			)
			(fill no)
			(layer "F.CrtYd")
		)
		(fp_rect
			(start -2.8194 3.6322)
			(end 2.8194 -3.6322)
			(stroke
				(width 0)
				(type default)
			)
			(fill no)
			(layer "F.Fab")
		)
		(pad "1" smd rect
			(at -1.905 2.54)
			(size 0.635 1.651)
			(layers "F.Cu" "F.Mask" "F.Paste")
			(net "P12V_A")
		)
		(pad "2" smd rect
			(at -0.635 2.54)
			(size 0.635 1.651)
			(layers "F.Cu" "F.Mask" "F.Paste")
			(net "P12V_A")
		)
		(pad "3" smd rect
			(at 0.635 2.54)
			(size 0.635 1.651)
			(layers "F.Cu" "F.Mask" "F.Paste")
			(net "P12V_A")
		)
		(pad "4" smd rect
			(at 1.905 2.54)
			(size 0.635 1.651)
			(layers "F.Cu" "F.Mask" "F.Paste")
			(net "SW_HDD_N32")
		)
		(pad "5" smd rect
			(at 1.905 -2.54)
			(size 0.635 1.651)
			(layers "F.Cu" "F.Mask" "F.Paste")
			(net "P12V_HDD32")
		)
		(pad "6" smd rect
			(at 0.635 -2.54)
			(size 0.635 1.651)
			(layers "F.Cu" "F.Mask" "F.Paste")
			(net "P12V_HDD32")
		)
		(pad "7" smd rect
			(at -0.635 -2.54)
			(size 0.635 1.651)
			(layers "F.Cu" "F.Mask" "F.Paste")
			(net "P12V_HDD32")
		)
		(pad "8" smd rect
			(at -1.905 -2.54)
			(size 0.635 1.651)
			(layers "F.Cu" "F.Mask" "F.Paste")
			(net "P12V_HDD32")
		)
	)
	(footprint ""
		(layer "F.Cu")
		(at 338.074 -279.443942 90)
		(property "Reference" "R284"
			(at 0 0 90)
			(layer "F.SilkS")
			(hide yes)
			(effects
				(font
					(size 1.27 1.27)
				)
			)
		)
		(property "Value" "200KR2F-L-GP"
			(at 0.064008 -3.993896 90)
			(unlocked yes)
			(layer "F.Fab")
			(hide yes)
			(effects
				(font
					(size 1.016 1.016)
					(thickness 0.1524)
				)
			)
		)
		(property "Device Type" "R402H16"
			(at 0.064008 -5.517896 90)
			(unlocked yes)
			(layer "F.Fab")
			(hide yes)
			(effects
				(font
					(size 1.016 1.016)
					(thickness 0.1524)
				)
			)
		)
		(duplicate_pad_numbers_are_jumpers no)
		(fp_line
			(start 0.508 -0.9398)
			(end -0.508 -0.9398)
			(stroke
				(width 0.1524)
				(type default)
			)
			(layer "F.SilkS")
		)
		(fp_line
			(start -0.508 -0.9398)
			(end -0.508 0.9398)
			(stroke
				(width 0.1524)
				(type default)
			)
			(layer "F.SilkS")
		)
		(fp_rect
			(start -0.508 0.9398)
			(end 0.508 -0.9398)
			(stroke
				(width 0)
				(type default)
			)
			(fill no)
			(layer "F.CrtYd")
		)
		(fp_rect
			(start -0.508 0.9398)
			(end 0.508 -0.9398)
			(stroke
				(width 0)
				(type default)
			)
			(fill no)
			(layer "F.Fab")
		)
		(pad "1" smd custom
			(at 0 -0.4445 90)
			(size 0.1397 0.1397)
			(layers "F.Cu" "F.Mask" "F.Paste")
			(net "SW_HDD_R6")
			(options
				(clearance outline)
				(anchor circle)
			)
			(primitives
				(gr_poly
					(pts
						(arc
							(start -0.1778 -0.2794)
							(mid -0.249642 -0.249642)
							(end -0.2794 -0.1778)
						)
						(arc
							(start -0.2794 0.1778)
							(mid -0.249642 0.249642)
							(end -0.1778 0.2794)
						)
						(arc
							(start 0.1778 0.2794)
							(mid 0.249642 0.249642)
							(end 0.2794 0.1778)
						)
						(arc
							(start 0.2794 -0.1778)
							(mid 0.249642 -0.249642)
							(end 0.1778 -0.2794)
						)
					)
					(width 0)
					(fill yes)
				)
			)
		)
		(pad "2" smd custom
			(at 0 0.4445 90)
			(size 0.1397 0.1397)
			(layers "F.Cu" "F.Mask" "F.Paste")
			(net "SW_HDD_N6")
			(options
				(clearance outline)
				(anchor circle)
			)
			(primitives
				(gr_poly
					(pts
						(arc
							(start -0.1778 -0.2794)
							(mid -0.249642 -0.249642)
							(end -0.2794 -0.1778)
						)
						(arc
							(start -0.2794 0.1778)
							(mid -0.249642 0.249642)
							(end -0.1778 0.2794)
						)
						(arc
							(start 0.1778 0.2794)
							(mid 0.249642 0.249642)
							(end 0.2794 0.1778)
						)
						(arc
							(start 0.2794 -0.1778)
							(mid 0.249642 -0.249642)
							(end 0.1778 -0.2794)
						)
					)
					(width 0)
					(fill yes)
				)
			)
		)
	)
)
